(kicad_pcb
	(version 20260206)
	(generator "pcbnew")
	(generator_version "10.0")
	(general
		(thickness 1.6)
		(legacy_teardrops no)
	)
	(paper "A4")
	(title_block
		(title "Wiwynn_Tioga_Pass_MB.brd")
		(comment 1 "Tioga Pass / footprints 926-933 of 4770")
	)
	(layers
		(0 "F.Cu" signal "TOP")
		(4 "In1.Cu" signal "L2GND")
		(6 "In2.Cu" signal "L3")
		(8 "In3.Cu" signal "L4GND")
		(10 "In4.Cu" signal "L5")
		(12 "In5.Cu" signal "L6GND")
		(14 "In6.Cu" signal "L7VCC")
		(16 "In7.Cu" signal "L8VCC")
		(18 "In8.Cu" signal "L9GND")
		(20 "In9.Cu" signal "L10")
		(22 "In10.Cu" signal "L11GND")
		(24 "In11.Cu" signal "L12")
		(26 "In12.Cu" signal "L13GND")
		(2 "B.Cu" signal "BOTTOM")
		(9 "F.Adhes" user "F.Adhesive")
		(11 "B.Adhes" user "B.Adhesive")
		(13 "F.Paste" user "Package Geometry/Pastemask Top")
		(15 "B.Paste" user "Package Geometry/Pastemask Bottom")
		(5 "F.SilkS" user "Ref Des/Silkscreen Top")
		(7 "B.SilkS" user "Ref Des/Silkscreen Bottom")
		(1 "F.Mask" user "Board Geometry/Soldermask Top")
		(3 "B.Mask" user "Board Geometry/Soldermask Bottom")
		(17 "Dwgs.User" user "User.Drawings")
		(19 "Cmts.User" user "User.Comments")
		(21 "Eco1.User" user "User.Eco1")
		(23 "Eco2.User" user "User.Eco2")
		(25 "Edge.Cuts" user "Board Geometry/Outline")
		(27 "Margin" user)
		(31 "F.CrtYd" user "Package Geometry/Place Bound Top")
		(29 "B.CrtYd" user "Package Geometry/Place Bound Bottom")
		(35 "F.Fab" user "Ref Des/Assembly Top")
		(33 "B.Fab" user "Ref Des/Assembly Bottom")
	)
	(footprint ""
		(layer "F.Cu")
		(at 100.683568 -79.6036 180)
		(property "Reference" "C2D15"
			(at 0 0 180)
			(layer "F.SilkS")
			(hide yes)
			(effects
				(font
					(size 1.27 1.27)
				)
			)
		)
		(property "Value" ""
			(at 0 0 180)
			(layer "F.Fab")
			(effects
				(font
					(size 1.27 1.27)
				)
			)
		)
		(duplicate_pad_numbers_are_jumpers no)
		(fp_poly
			(pts
				(xy -0.4953 -0.2032) (xy 0.4953 -0.2032) (xy 0.4953 1.6002) (xy -0.4953 1.6002)
			)
			(stroke
				(width 0)
				(type default)
			)
			(fill no)
			(layer "F.CrtYd")
		)
		(fp_line
			(start 0.4953 1.6002)
			(end -0.4953 1.6002)
			(stroke
				(width 0.1)
				(type default)
			)
			(layer "F.Fab")
		)
		(fp_line
			(start 0.4953 -0.2032)
			(end 0.4953 1.6002)
			(stroke
				(width 0.1)
				(type default)
			)
			(layer "F.Fab")
		)
		(fp_line
			(start -0.4953 1.6002)
			(end -0.4953 -0.2032)
			(stroke
				(width 0.1)
				(type default)
			)
			(layer "F.Fab")
		)
		(fp_line
			(start -0.4953 -0.2032)
			(end 0.4953 -0.2032)
			(stroke
				(width 0.1)
				(type default)
			)
			(layer "F.Fab")
		)
		(pad "1" smd rect
			(at 0 0 180)
			(size 0.762 0.889)
			(layers "F.Cu" "F.Mask" "F.Paste")
			(net "PVCCIN_CPU1")
		)
		(pad "2" smd rect
			(at 0 1.397 180)
			(size 0.762 0.889)
			(layers "F.Cu" "F.Mask" "F.Paste")
			(net "GND")
		)
		(zone
			(layer "F.Cu")
			(hatch none 0.5)
			(connect_pads
				(clearance 0)
			)
			(min_thickness 0.25)
			(keepout
				(tracks not_allowed)
				(vias allowed)
				(pads allowed)
				(copperpour not_allowed)
				(footprints allowed)
			)
			(placement
				(enabled no)
				(sheetname "")
			)
			(fill
				(thermal_gap 0.5)
				(thermal_bridge_width 0.5)
				(island_removal_mode 0)
			)
			(polygon
				(pts
					(xy 101.064568 -80.0481) (xy 100.302568 -80.0481) (xy 100.302568 -80.5561) (xy 101.064568 -80.5561)
				)
			)
		)
	)
	(footprint ""
		(layer "F.Cu")
		(at 189.963044 -66.080386 180)
		(property "Reference" "RF2"
			(at -0.8382 -0.67818 180)
			(unlocked yes)
			(layer "F.SilkS")
			(effects
				(font
					(size 0.4064 0.254)
					(thickness 0.1524)
				)
				(justify left)
			)
		)
		(property "Value" ""
			(at 0 0 180)
			(layer "F.Fab")
			(effects
				(font
					(size 1.27 1.27)
				)
			)
		)
		(duplicate_pad_numbers_are_jumpers no)
		(fp_poly
			(pts
				(xy -0.2794 -0.1016) (xy 0.2794 -0.1016) (xy 0.2794 0.9906) (xy -0.2794 0.9906)
			)
			(stroke
				(width 0)
				(type default)
			)
			(fill no)
			(layer "F.CrtYd")
		)
		(fp_line
			(start 0.2794 0.9906)
			(end 0.2794 -0.1016)
			(stroke
				(width 0.1)
				(type default)
			)
			(layer "F.Fab")
		)
		(fp_line
			(start 0.2794 -0.1016)
			(end -0.2794 -0.1016)
			(stroke
				(width 0.1)
				(type default)
			)
			(layer "F.Fab")
		)
		(fp_line
			(start -0.2794 0.9906)
			(end 0.2794 0.9906)
			(stroke
				(width 0.1)
				(type default)
			)
			(layer "F.Fab")
		)
		(fp_line
			(start -0.2794 -0.1016)
			(end -0.2794 0.9906)
			(stroke
				(width 0.1)
				(type default)
			)
			(layer "F.Fab")
		)
		(pad "1" smd rect
			(at 0 0 180)
			(size 0.508 0.508)
			(layers "F.Cu" "F.Mask" "F.Paste")
			(net "VR_PVCCIN_CPU0_AIREF2")
		)
		(pad "2" smd rect
			(at 0 0.889 180)
			(size 0.508 0.508)
			(layers "F.Cu" "F.Mask" "F.Paste")
			(net "ISENSE_PVCCIN_CPU0_PH2_IMON")
		)
		(zone
			(layer "F.Cu")
			(hatch none 0.5)
			(connect_pads
				(clearance 0)
			)
			(min_thickness 0.25)
			(keepout
				(tracks not_allowed)
				(vias allowed)
				(pads allowed)
				(copperpour not_allowed)
				(footprints allowed)
			)
			(placement
				(enabled no)
				(sheetname "")
			)
			(fill
				(thermal_gap 0.5)
				(thermal_bridge_width 0.5)
				(island_removal_mode 0)
			)
			(polygon
				(pts
					(xy 190.217044 -66.715386) (xy 189.709044 -66.715386) (xy 189.709044 -66.334386) (xy 190.217044 -66.334386)
				)
			)
		)
		(zone
			(layer "F.Cu")
			(hatch none 0.5)
			(connect_pads
				(clearance 0)
			)
			(min_thickness 0.25)
			(keepout
				(tracks allowed)
				(vias not_allowed)
				(pads allowed)
				(copperpour not_allowed)
				(footprints allowed)
			)
			(placement
				(enabled no)
				(sheetname "")
			)
			(fill
				(thermal_gap 0.5)
				(thermal_bridge_width 0.5)
				(island_removal_mode 0)
			)
			(polygon
				(pts
					(xy 190.217044 -66.334386) (xy 189.709044 -66.334386) (xy 189.709044 -66.715386) (xy 190.217044 -66.715386)
				)
			)
		)
	)
	(footprint ""
		(layer "F.Cu")
		(at 23.241 -81.6102)
		(property "Reference" "R1D20"
			(at 0 0 0)
			(layer "F.SilkS")
			(hide yes)
			(effects
				(font
					(size 1.27 1.27)
				)
			)
		)
		(property "Value" ""
			(at 0 0 0)
			(layer "F.Fab")
			(effects
				(font
					(size 1.27 1.27)
				)
			)
		)
		(duplicate_pad_numbers_are_jumpers no)
		(fp_poly
			(pts
				(xy -0.2794 -0.1016) (xy 0.2794 -0.1016) (xy 0.2794 0.9906) (xy -0.2794 0.9906)
			)
			(stroke
				(width 0)
				(type default)
			)
			(fill no)
			(layer "F.CrtYd")
		)
		(fp_line
			(start -0.2794 -0.1016)
			(end -0.2794 0.9906)
			(stroke
				(width 0.1)
				(type default)
			)
			(layer "F.Fab")
		)
		(fp_line
			(start -0.2794 0.9906)
			(end 0.2794 0.9906)
			(stroke
				(width 0.1)
				(type default)
			)
			(layer "F.Fab")
		)
		(fp_line
			(start 0.2794 -0.1016)
			(end -0.2794 -0.1016)
			(stroke
				(width 0.1)
				(type default)
			)
			(layer "F.Fab")
		)
		(fp_line
			(start 0.2794 0.9906)
			(end 0.2794 -0.1016)
			(stroke
				(width 0.1)
				(type default)
			)
			(layer "F.Fab")
		)
		(pad "1" smd rect
			(at 0 0)
			(size 0.508 0.508)
			(layers "F.Cu" "F.Mask" "F.Paste")
			(net "A_HSC_CSOUT")
		)
		(pad "2" smd rect
			(at 0 0.889)
			(size 0.508 0.508)
			(layers "F.Cu" "F.Mask" "F.Paste")
			(net "A_HSC_HIGH")
		)
		(zone
			(layer "F.Cu")
			(hatch none 0.5)
			(connect_pads
				(clearance 0)
			)
			(min_thickness 0.25)
			(keepout
				(tracks allowed)
				(vias not_allowed)
				(pads allowed)
				(copperpour not_allowed)
				(footprints allowed)
			)
			(placement
				(enabled no)
				(sheetname "")
			)
			(fill
				(thermal_gap 0.5)
				(thermal_bridge_width 0.5)
				(island_removal_mode 0)
			)
			(polygon
				(pts
					(xy 22.987 -81.3562) (xy 23.495 -81.3562) (xy 23.495 -80.9752) (xy 22.987 -80.9752)
				)
			)
		)
		(zone
			(layer "F.Cu")
			(hatch none 0.5)
			(connect_pads
				(clearance 0)
			)
			(min_thickness 0.25)
			(keepout
				(tracks not_allowed)
				(vias allowed)
				(pads allowed)
				(copperpour not_allowed)
				(footprints allowed)
			)
			(placement
				(enabled no)
				(sheetname "")
			)
			(fill
				(thermal_gap 0.5)
				(thermal_bridge_width 0.5)
				(island_removal_mode 0)
			)
			(polygon
				(pts
					(xy 22.987 -80.9752) (xy 23.495 -80.9752) (xy 23.495 -81.3562) (xy 22.987 -81.3562)
				)
			)
		)
	)
	(footprint ""
		(layer "F.Cu")
		(at 401.066 -47.9425)
		(property "Reference" "R7F32"
			(at 0 0 0)
			(layer "F.SilkS")
			(hide yes)
			(effects
				(font
					(size 1.27 1.27)
				)
			)
		)
		(property "Value" ""
			(at 0 0 0)
			(layer "F.Fab")
			(effects
				(font
					(size 1.27 1.27)
				)
			)
		)
		(duplicate_pad_numbers_are_jumpers no)
		(fp_poly
			(pts
				(xy -0.2794 -0.1016) (xy 0.2794 -0.1016) (xy 0.2794 0.9906) (xy -0.2794 0.9906)
			)
			(stroke
				(width 0)
				(type default)
			)
			(fill no)
			(layer "F.CrtYd")
		)
		(fp_line
			(start -0.2794 -0.1016)
			(end -0.2794 0.9906)
			(stroke
				(width 0.1)
				(type default)
			)
			(layer "F.Fab")
		)
		(fp_line
			(start -0.2794 0.9906)
			(end 0.2794 0.9906)
			(stroke
				(width 0.1)
				(type default)
			)
			(layer "F.Fab")
		)
		(fp_line
			(start 0.2794 -0.1016)
			(end -0.2794 -0.1016)
			(stroke
				(width 0.1)
				(type default)
			)
			(layer "F.Fab")
		)
		(fp_line
			(start 0.2794 0.9906)
			(end 0.2794 -0.1016)
			(stroke
				(width 0.1)
				(type default)
			)
			(layer "F.Fab")
		)
		(pad "1" smd rect
			(at 0 0)
			(size 0.508 0.508)
			(layers "F.Cu" "F.Mask" "F.Paste")
			(net "P3V3_STBY")
		)
		(pad "2" smd rect
			(at 0 0.889)
			(size 0.508 0.508)
			(layers "F.Cu" "F.Mask" "F.Paste")
			(net "PU_BIOS_SPI_HOLD0_N")
		)
		(zone
			(layer "F.Cu")
			(hatch none 0.5)
			(connect_pads
				(clearance 0)
			)
			(min_thickness 0.25)
			(keepout
				(tracks allowed)
				(vias not_allowed)
				(pads allowed)
				(copperpour not_allowed)
				(footprints allowed)
			)
			(placement
				(enabled no)
				(sheetname "")
			)
			(fill
				(thermal_gap 0.5)
				(thermal_bridge_width 0.5)
				(island_removal_mode 0)
			)
			(polygon
				(pts
					(xy 400.812 -47.6885) (xy 401.32 -47.6885) (xy 401.32 -47.3075) (xy 400.812 -47.3075)
				)
			)
		)
		(zone
			(layer "F.Cu")
			(hatch none 0.5)
			(connect_pads
				(clearance 0)
			)
			(min_thickness 0.25)
			(keepout
				(tracks not_allowed)
				(vias allowed)
				(pads allowed)
				(copperpour not_allowed)
				(footprints allowed)
			)
			(placement
				(enabled no)
				(sheetname "")
			)
			(fill
				(thermal_gap 0.5)
				(thermal_bridge_width 0.5)
				(island_removal_mode 0)
			)
			(polygon
				(pts
					(xy 400.812 -47.3075) (xy 401.32 -47.3075) (xy 401.32 -47.6885) (xy 400.812 -47.6885)
				)
			)
		)
	)
	(footprint ""
		(layer "F.Cu")
		(at 13.843 -142.875 -90)
		(property "Reference" "C1A12"
			(at 1.47828 0.78994 180)
			(unlocked yes)
			(layer "F.SilkS")
			(effects
				(font
					(size 0.4064 0.254)
					(thickness 0.1524)
				)
			)
		)
		(property "Value" ""
			(at 0 0 270)
			(layer "F.Fab")
			(effects
				(font
					(size 1.27 1.27)
				)
			)
		)
		(duplicate_pad_numbers_are_jumpers no)
		(fp_poly
			(pts
				(xy -0.7239 -0.2159) (xy 0.7239 -0.2159) (xy 0.7239 1.9939) (xy -0.7239 1.9939)
			)
			(stroke
				(width 0)
				(type default)
			)
			(fill no)
			(layer "F.CrtYd")
		)
		(fp_line
			(start -0.7239 1.9939)
			(end 0.7239 1.9939)
			(stroke
				(width 0.1)
				(type default)
			)
			(layer "F.Fab")
		)
		(fp_line
			(start 0.7239 1.9939)
			(end 0.7239 -0.2159)
			(stroke
				(width 0.1)
				(type default)
			)
			(layer "F.Fab")
		)
		(fp_line
			(start -0.7239 -0.2159)
			(end -0.7239 1.9939)
			(stroke
				(width 0.1)
				(type default)
			)
			(layer "F.Fab")
		)
		(fp_line
			(start 0.7239 -0.2159)
			(end -0.7239 -0.2159)
			(stroke
				(width 0.1)
				(type default)
			)
			(layer "F.Fab")
		)
		(pad "1" smd rect
			(at 0 0 270)
			(size 1.27 1.016)
			(layers "F.Cu" "F.Mask" "F.Paste")
			(net "PVDDQ_KLM")
		)
		(pad "2" smd rect
			(at 0 1.778 270)
			(size 1.27 1.016)
			(layers "F.Cu" "F.Mask" "F.Paste")
			(net "GND")
		)
		(zone
			(layer "F.Cu")
			(hatch none 0.5)
			(connect_pads
				(clearance 0)
			)
			(min_thickness 0.25)
			(keepout
				(tracks not_allowed)
				(vias allowed)
				(pads allowed)
				(copperpour not_allowed)
				(footprints allowed)
			)
			(placement
				(enabled no)
				(sheetname "")
			)
			(fill
				(thermal_gap 0.5)
				(thermal_bridge_width 0.5)
				(island_removal_mode 0)
			)
			(polygon
				(pts
					(xy 13.335 -143.51) (xy 13.335 -142.24) (xy 12.573 -142.24) (xy 12.573 -143.51)
				)
			)
		)
	)
	(footprint ""
		(layer "F.Cu")
		(at 448.35572 -153.54046 -90)
		(property "Reference" "R25W187"
			(at -0.8382 -0.67818 270)
			(unlocked yes)
			(layer "F.SilkS")
			(effects
				(font
					(size 0.4064 0.254)
					(thickness 0.1524)
				)
				(justify left)
			)
		)
		(property "Value" ""
			(at 0 0 270)
			(layer "F.Fab")
			(effects
				(font
					(size 1.27 1.27)
				)
			)
		)
		(duplicate_pad_numbers_are_jumpers no)
		(fp_poly
			(pts
				(xy -0.2794 -0.1016) (xy 0.2794 -0.1016) (xy 0.2794 0.9906) (xy -0.2794 0.9906)
			)
			(stroke
				(width 0)
				(type default)
			)
			(fill no)
			(layer "F.CrtYd")
		)
		(fp_line
			(start -0.2794 0.9906)
			(end 0.2794 0.9906)
			(stroke
				(width 0.1)
				(type default)
			)
			(layer "F.Fab")
		)
		(fp_line
			(start 0.2794 0.9906)
			(end 0.2794 -0.1016)
			(stroke
				(width 0.1)
				(type default)
			)
			(layer "F.Fab")
		)
		(fp_line
			(start -0.2794 -0.1016)
			(end -0.2794 0.9906)
			(stroke
				(width 0.1)
				(type default)
			)
			(layer "F.Fab")
		)
		(fp_line
			(start 0.2794 -0.1016)
			(end -0.2794 -0.1016)
			(stroke
				(width 0.1)
				(type default)
			)
			(layer "F.Fab")
		)
		(pad "1" smd rect
			(at 0 0 270)
			(size 0.508 0.508)
			(layers "F.Cu" "F.Mask" "F.Paste")
			(net "JTAG_BMC_BUF_TDO_R")
		)
		(pad "2" smd rect
			(at 0 0.889 270)
			(size 0.508 0.508)
			(layers "F.Cu" "F.Mask" "F.Paste")
			(net "JTAG_BMC_BUF_TDO")
		)
		(zone
			(layer "F.Cu")
			(hatch none 0.5)
			(connect_pads
				(clearance 0)
			)
			(min_thickness 0.25)
			(keepout
				(tracks not_allowed)
				(vias allowed)
				(pads allowed)
				(copperpour not_allowed)
				(footprints allowed)
			)
			(placement
				(enabled no)
				(sheetname "")
			)
			(fill
				(thermal_gap 0.5)
				(thermal_bridge_width 0.5)
				(island_removal_mode 0)
			)
			(polygon
				(pts
					(xy 447.72072 -153.79446) (xy 447.72072 -153.28646) (xy 448.10172 -153.28646) (xy 448.10172 -153.79446)
				)
			)
		)
		(zone
			(layer "F.Cu")
			(hatch none 0.5)
			(connect_pads
				(clearance 0)
			)
			(min_thickness 0.25)
			(keepout
				(tracks allowed)
				(vias not_allowed)
				(pads allowed)
				(copperpour not_allowed)
				(footprints allowed)
			)
			(placement
				(enabled no)
				(sheetname "")
			)
			(fill
				(thermal_gap 0.5)
				(thermal_bridge_width 0.5)
				(island_removal_mode 0)
			)
			(polygon
				(pts
					(xy 448.10172 -153.79446) (xy 448.10172 -153.28646) (xy 447.72072 -153.28646) (xy 447.72072 -153.79446)
				)
			)
		)
	)
	(footprint ""
		(layer "F.Cu")
		(at 453.644 -41.021)
		(property "Reference" "R9F34"
			(at 0 0 0)
			(layer "F.SilkS")
			(hide yes)
			(effects
				(font
					(size 1.27 1.27)
				)
			)
		)
		(property "Value" ""
			(at 0 0 0)
			(layer "F.Fab")
			(effects
				(font
					(size 1.27 1.27)
				)
			)
		)
		(duplicate_pad_numbers_are_jumpers no)
		(fp_poly
			(pts
				(xy -0.2794 -0.1016) (xy 0.2794 -0.1016) (xy 0.2794 0.9906) (xy -0.2794 0.9906)
			)
			(stroke
				(width 0)
				(type default)
			)
			(fill no)
			(layer "F.CrtYd")
		)
		(fp_line
			(start -0.2794 -0.1016)
			(end -0.2794 0.9906)
			(stroke
				(width 0.1)
				(type default)
			)
			(layer "F.Fab")
		)
		(fp_line
			(start -0.2794 0.9906)
			(end 0.2794 0.9906)
			(stroke
				(width 0.1)
				(type default)
			)
			(layer "F.Fab")
		)
		(fp_line
			(start 0.2794 -0.1016)
			(end -0.2794 -0.1016)
			(stroke
				(width 0.1)
				(type default)
			)
			(layer "F.Fab")
		)
		(fp_line
			(start 0.2794 0.9906)
			(end 0.2794 -0.1016)
			(stroke
				(width 0.1)
				(type default)
			)
			(layer "F.Fab")
		)
		(pad "1" smd rect
			(at 0 0)
			(size 0.508 0.508)
			(layers "F.Cu" "F.Mask" "F.Paste")
			(net "RST_BMC_DDR3_R_N")
		)
		(pad "2" smd rect
			(at 0 0.889)
			(size 0.508 0.508)
			(layers "F.Cu" "F.Mask" "F.Paste")
			(net "BMC_M_RST_N")
		)
		(zone
			(layer "F.Cu")
			(hatch none 0.5)
			(connect_pads
				(clearance 0)
			)
			(min_thickness 0.25)
			(keepout
				(tracks allowed)
				(vias not_allowed)
				(pads allowed)
				(copperpour not_allowed)
				(footprints allowed)
			)
			(placement
				(enabled no)
				(sheetname "")
			)
			(fill
				(thermal_gap 0.5)
				(thermal_bridge_width 0.5)
				(island_removal_mode 0)
			)
			(polygon
				(pts
					(xy 453.39 -40.767) (xy 453.898 -40.767) (xy 453.898 -40.386) (xy 453.39 -40.386)
				)
			)
		)
		(zone
			(layer "F.Cu")
			(hatch none 0.5)
			(connect_pads
				(clearance 0)
			)
			(min_thickness 0.25)
			(keepout
				(tracks not_allowed)
				(vias allowed)
				(pads allowed)
				(copperpour not_allowed)
				(footprints allowed)
			)
			(placement
				(enabled no)
				(sheetname "")
			)
			(fill
				(thermal_gap 0.5)
				(thermal_bridge_width 0.5)
				(island_removal_mode 0)
			)
			(polygon
				(pts
					(xy 453.39 -40.386) (xy 453.898 -40.386) (xy 453.898 -40.767) (xy 453.39 -40.767)
				)
			)
		)
	)
	(footprint ""
		(layer "F.Cu")
		(at 477.3041 -42.1894 90)
		(property "Reference" "R9E18"
			(at 0 0 90)
			(layer "F.SilkS")
			(hide yes)
			(effects
				(font
					(size 1.27 1.27)
				)
			)
		)
		(property "Value" ""
			(at 0 0 90)
			(layer "F.Fab")
			(effects
				(font
					(size 1.27 1.27)
				)
			)
		)
		(duplicate_pad_numbers_are_jumpers no)
		(fp_poly
			(pts
				(xy -0.2794 -0.1016) (xy 0.2794 -0.1016) (xy 0.2794 0.9906) (xy -0.2794 0.9906)
			)
			(stroke
				(width 0)
				(type default)
			)
			(fill no)
			(layer "F.CrtYd")
		)
		(fp_line
			(start 0.2794 -0.1016)
			(end -0.2794 -0.1016)
			(stroke
				(width 0.1)
				(type default)
			)
			(layer "F.Fab")
		)
		(fp_line
			(start -0.2794 -0.1016)
			(end -0.2794 0.9906)
			(stroke
				(width 0.1)
				(type default)
			)
			(layer "F.Fab")
		)
		(fp_line
			(start 0.2794 0.9906)
			(end 0.2794 -0.1016)
			(stroke
				(width 0.1)
				(type default)
			)
			(layer "F.Fab")
		)
		(fp_line
			(start -0.2794 0.9906)
			(end 0.2794 0.9906)
			(stroke
				(width 0.1)
				(type default)
			)
			(layer "F.Fab")
		)
		(pad "1" smd rect
			(at 0 0 90)
			(size 0.508 0.508)
			(layers "F.Cu" "F.Mask" "F.Paste")
			(net "XTAL_25MHZ_OUT_R")
		)
		(pad "2" smd rect
			(at 0 0.889 90)
			(size 0.508 0.508)
			(layers "F.Cu" "F.Mask" "F.Paste")
			(net "XTAL_25MHZ_OUT")
		)
		(zone
			(layer "F.Cu")
			(hatch none 0.5)
			(connect_pads
				(clearance 0)
			)
			(min_thickness 0.25)
			(keepout
				(tracks allowed)
				(vias not_allowed)
				(pads allowed)
				(copperpour not_allowed)
				(footprints allowed)
			)
			(placement
				(enabled no)
				(sheetname "")
			)
			(fill
				(thermal_gap 0.5)
				(thermal_bridge_width 0.5)
				(island_removal_mode 0)
			)
			(polygon
				(pts
					(xy 477.5581 -41.9354) (xy 477.5581 -42.4434) (xy 477.9391 -42.4434) (xy 477.9391 -41.9354)
				)
			)
		)
		(zone
			(layer "F.Cu")
			(hatch none 0.5)
			(connect_pads
				(clearance 0)
			)
			(min_thickness 0.25)
			(keepout
				(tracks not_allowed)
				(vias allowed)
				(pads allowed)
				(copperpour not_allowed)
				(footprints allowed)
			)
			(placement
				(enabled no)
				(sheetname "")
			)
			(fill
				(thermal_gap 0.5)
				(thermal_bridge_width 0.5)
				(island_removal_mode 0)
			)
			(polygon
				(pts
					(xy 477.9391 -41.9354) (xy 477.9391 -42.4434) (xy 477.5581 -42.4434) (xy 477.5581 -41.9354)
				)
			)
		)
	)
)
